# Bryce Canyon_Front_Drive_Plane_Board_Stackup.xlsx — PCB Test Plan_HVM(90+) (pcb-stackup)
|  | Board vendor give feedback of quantity in yellow columns based on the AQL table or description. |  |  |  |  |  |  |  |  |  |  |  |  |  |  |
|  | Wiwynn PM give feedback in blue columns |  |  |  |  |  |  |  |  |  |  |  |  |  |  |
| Person to be informed : PCB vendor, EE, SI, PM, PSM, Buyer, SQM |  |  |  |  |  |  |  |  |  |  |  |  |  |  |  |
| Simple flow : SI (test requirements) -> PM/AM (Total PCBS demand) -> Buyer -> Board Vendor (yellow column feedback) -> Buyer -> Person to be informed (Check and Track) |  |  |  |  |  |  |  |  |  |  |  |  |  |  |  |
| PO(purchase order) : If there are many POs for this PCB, 1st sample quantity is based on 1st PO, 2nd sample quantity is based on 2nd PO. |  |  |  |  |  |  |  |  |  |  |  |  |  |  |  |
| Project Name | PCB name | PCB# (1XXXX-XX) | Product Stage | Batch# | PCB Vendor | Production  Lot size | PCBs Demand | Delta-L Coupon (PCB Vendor) | Delta-L Coupon (3rd Party Lab) | Impedance Coupon (PCB Vendor) | In-board trace correlation (PCB Vendor) | X-section Analysis (PCB Vendor) | IST (3rd Party Lab) | IPC-6012D (3rd Party Lab) | Note |
| Bryce Canyon | FDPB | 16315-1 | HVM(90+ days) | N/A |  |  | TBD | Yes | No | Yes | No | No | No | No | Need Test? (Yes, No) |
| Tracking Code On Both Of Coupon And PCB |  |  |  |  |  |  |  | N/A |  | N/A |  |  |  |  |  |
| Test Item Acceptance Criteria |  |  |  |  |  |  |  | c = 0 |  | c = 0 |  |  |  |  |  |
| Test Item Sampling Quantity |  |  |  |  |  |  |  | 5 pcs/production lot/quarter, with max total of 30 pcs |  | Mil-STD 105E single sampling plan, AQL 0.65, level 2 |  |  |  |  |  |
| Test Time(working days) |  |  |  |  |  |  |  |  |  |  |  |  |  |  |  |
| Test Item Shipping Quantity |  |  |  |  |  |  |  |  |  |  |  |  |  |  |  |
| Shipping Address |  |  |  |  |  |  |  |  |  |  |  |  |  |  |  |
| Receiver Name |  |  |  |  |  |  |  |  |  |  |  |  |  |  |  |
| Receiver Phone# |  |  |  |  |  |  |  |  |  |  |  |  |  |  |  |
